(kicad_pcb
	(version 20260206)
	(generator "pcbnew")
	(generator_version "10.0")
	(general
		(thickness 1.6)
		(legacy_teardrops no)
	)
	(paper "A4")
	(title_block
		(title "03242023_DA0F0TMBIJ0_F0T_Motherboard_J_brd_V01_OCP.brd")
		(comment 1 "Grand Teton / footprints 2577-2582 of 6105")
	)
	(layers
		(0 "F.Cu" signal "TOP")
		(4 "In1.Cu" signal "GND")
		(6 "In2.Cu" signal "IN1")
		(8 "In3.Cu" signal "GND1")
		(10 "In4.Cu" signal "IN2")
		(12 "In5.Cu" signal "GND2")
		(14 "In6.Cu" signal "IN3")
		(16 "In7.Cu" signal "GND3")
		(18 "In8.Cu" signal "VCC")
		(20 "In9.Cu" signal "VCC1")
		(22 "In10.Cu" signal "GND4")
		(24 "In11.Cu" signal "IN4")
		(26 "In12.Cu" signal "GND5")
		(28 "In13.Cu" signal "IN5")
		(30 "In14.Cu" signal "GND6")
		(32 "In15.Cu" signal "IN6")
		(34 "In16.Cu" signal "GND7")
		(2 "B.Cu" signal "BOTTOM")
		(9 "F.Adhes" user "F.Adhesive")
		(11 "B.Adhes" user "B.Adhesive")
		(13 "F.Paste" user "Package Geometry/Pastemask Top")
		(15 "B.Paste" user "Package Geometry/Pastemask Bottom")
		(5 "F.SilkS" user "Ref Des/Silkscreen Top")
		(7 "B.SilkS" user "Ref Des/Silkscreen Bottom")
		(1 "F.Mask" user "Board Geometry/Soldermask Top")
		(3 "B.Mask" user "Board Geometry/Soldermask Bottom")
		(17 "Dwgs.User" user "User.Drawings")
		(19 "Cmts.User" user "User.Comments")
		(21 "Eco1.User" user "User.Eco1")
		(23 "Eco2.User" user "User.Eco2")
		(25 "Edge.Cuts" user "Board Geometry/Outline")
		(27 "Margin" user)
		(31 "F.CrtYd" user "Package Geometry/Place Bound Top")
		(29 "B.CrtYd" user "Package Geometry/Place Bound Bottom")
		(35 "F.Fab" user "Ref Des/Assembly Top")
		(33 "B.Fab" user "Ref Des/Assembly Bottom")
	)
	(footprint ""
		(layer "F.Cu")
		(at 107.28833 -241.97691 -90)
		(property "Reference" "C284"
			(at 0 0 270)
			(layer "F.SilkS")
			(hide yes)
			(effects
				(font
					(size 1.27 1.27)
				)
			)
		)
		(property "Value" ""
			(at 0 0 270)
			(layer "F.Fab")
			(effects
				(font
					(size 1.27 1.27)
				)
			)
		)
		(duplicate_pad_numbers_are_jumpers no)
		(fp_line
			(start -0.7874 0.4064)
			(end -0.7874 -0.4064)
			(stroke
				(width 0.1524)
				(type default)
			)
			(layer "F.SilkS")
		)
		(fp_line
			(start 0.7874 0.4064)
			(end -0.7874 0.4064)
			(stroke
				(width 0.1524)
				(type default)
			)
			(layer "F.SilkS")
		)
		(fp_line
			(start -0.7874 -0.4064)
			(end 0.7874 -0.4064)
			(stroke
				(width 0.1524)
				(type default)
			)
			(layer "F.SilkS")
		)
		(fp_line
			(start 0.7874 -0.4064)
			(end 0.7874 0.4064)
			(stroke
				(width 0.1524)
				(type default)
			)
			(layer "F.SilkS")
		)
		(fp_line
			(start -0.67945 0.3048)
			(end -0.67945 -0.305054)
			(stroke
				(width 0.1)
				(type default)
			)
			(layer "F.Fab")
		)
		(fp_line
			(start -0.12065 0.3048)
			(end -0.67945 0.3048)
			(stroke
				(width 0.1)
				(type default)
			)
			(layer "F.Fab")
		)
		(fp_line
			(start 0.120396 0.3048)
			(end 0.120396 0.2794)
			(stroke
				(width 0.1)
				(type default)
			)
			(layer "F.Fab")
		)
		(fp_line
			(start 0.67945 0.3048)
			(end 0.120396 0.3048)
			(stroke
				(width 0.1)
				(type default)
			)
			(layer "F.Fab")
		)
		(fp_line
			(start -0.12065 0.2794)
			(end -0.12065 0.3048)
			(stroke
				(width 0.1)
				(type default)
			)
			(layer "F.Fab")
		)
		(fp_line
			(start 0.120396 0.2794)
			(end -0.12065 0.2794)
			(stroke
				(width 0.1)
				(type default)
			)
			(layer "F.Fab")
		)
		(fp_line
			(start -0.12065 -0.2794)
			(end 0.12065 -0.2794)
			(stroke
				(width 0.1)
				(type default)
			)
			(layer "F.Fab")
		)
		(fp_line
			(start 0.12065 -0.2794)
			(end 0.12065 -0.3048)
			(stroke
				(width 0.1)
				(type default)
			)
			(layer "F.Fab")
		)
		(fp_line
			(start 0.12065 -0.3048)
			(end 0.67945 -0.3048)
			(stroke
				(width 0.1)
				(type default)
			)
			(layer "F.Fab")
		)
		(fp_line
			(start 0.67945 -0.3048)
			(end 0.67945 0.3048)
			(stroke
				(width 0.1)
				(type default)
			)
			(layer "F.Fab")
		)
		(fp_line
			(start -0.67945 -0.305054)
			(end -0.12065 -0.305054)
			(stroke
				(width 0.1)
				(type default)
			)
			(layer "F.Fab")
		)
		(fp_line
			(start -0.12065 -0.305054)
			(end -0.12065 -0.2794)
			(stroke
				(width 0.1)
				(type default)
			)
			(layer "F.Fab")
		)
		(pad "1" smd circle
			(at -0.40005 0 270)
			(size 0 0)
			(layers "F.Cu" "F.Mask" "F.Paste")
			(net "PVCCIN_CPU1")
		)
		(pad "2" smd circle
			(at 0.40005 0 270)
			(size 0 0)
			(layers "F.Cu" "F.Mask" "F.Paste")
			(net "GND")
		)
	)
	(footprint ""
		(layer "F.Cu")
		(at 448.61988 -94.602808 180)
		(property "Reference" "R4094"
			(at 0 0 180)
			(layer "F.SilkS")
			(hide yes)
			(effects
				(font
					(size 1.27 1.27)
				)
			)
		)
		(property "Value" ""
			(at 0 0 180)
			(layer "F.Fab")
			(effects
				(font
					(size 1.27 1.27)
				)
			)
		)
		(duplicate_pad_numbers_are_jumpers no)
		(fp_line
			(start 0.7874 0.4064)
			(end -0.7874 0.4064)
			(stroke
				(width 0.1524)
				(type default)
			)
			(layer "F.SilkS")
		)
		(fp_line
			(start 0.7874 -0.4064)
			(end 0.7874 0.4064)
			(stroke
				(width 0.1524)
				(type default)
			)
			(layer "F.SilkS")
		)
		(fp_line
			(start -0.7874 0.4064)
			(end -0.7874 -0.4064)
			(stroke
				(width 0.1524)
				(type default)
			)
			(layer "F.SilkS")
		)
		(fp_line
			(start -0.7874 -0.4064)
			(end 0.7874 -0.4064)
			(stroke
				(width 0.1524)
				(type default)
			)
			(layer "F.SilkS")
		)
		(fp_line
			(start 0.67945 0.3048)
			(end 0.120396 0.3048)
			(stroke
				(width 0.1)
				(type default)
			)
			(layer "F.Fab")
		)
		(fp_line
			(start 0.67945 -0.3048)
			(end 0.67945 0.3048)
			(stroke
				(width 0.1)
				(type default)
			)
			(layer "F.Fab")
		)
		(fp_line
			(start 0.12065 -0.2794)
			(end 0.12065 -0.3048)
			(stroke
				(width 0.1)
				(type default)
			)
			(layer "F.Fab")
		)
		(fp_line
			(start 0.12065 -0.3048)
			(end 0.67945 -0.3048)
			(stroke
				(width 0.1)
				(type default)
			)
			(layer "F.Fab")
		)
		(fp_line
			(start 0.120396 0.3048)
			(end 0.120396 0.2794)
			(stroke
				(width 0.1)
				(type default)
			)
			(layer "F.Fab")
		)
		(fp_line
			(start 0.120396 0.2794)
			(end -0.12065 0.2794)
			(stroke
				(width 0.1)
				(type default)
			)
			(layer "F.Fab")
		)
		(fp_line
			(start -0.12065 0.3048)
			(end -0.67945 0.3048)
			(stroke
				(width 0.1)
				(type default)
			)
			(layer "F.Fab")
		)
		(fp_line
			(start -0.12065 0.2794)
			(end -0.12065 0.3048)
			(stroke
				(width 0.1)
				(type default)
			)
			(layer "F.Fab")
		)
		(fp_line
			(start -0.12065 -0.2794)
			(end 0.12065 -0.2794)
			(stroke
				(width 0.1)
				(type default)
			)
			(layer "F.Fab")
		)
		(fp_line
			(start -0.12065 -0.305054)
			(end -0.12065 -0.2794)
			(stroke
				(width 0.1)
				(type default)
			)
			(layer "F.Fab")
		)
		(fp_line
			(start -0.67945 0.3048)
			(end -0.67945 -0.305054)
			(stroke
				(width 0.1)
				(type default)
			)
			(layer "F.Fab")
		)
		(fp_line
			(start -0.67945 -0.305054)
			(end -0.12065 -0.305054)
			(stroke
				(width 0.1)
				(type default)
			)
			(layer "F.Fab")
		)
		(pad "1" smd circle
			(at -0.40005 0 180)
			(size 0 0)
			(layers "F.Cu" "F.Mask" "F.Paste")
			(net "P3V3_AUX")
		)
		(pad "2" smd circle
			(at 0.40005 0 180)
			(size 0 0)
			(layers "F.Cu" "F.Mask" "F.Paste")
			(net "OCP_SFF_P3V3_ADC_ALERT_R")
		)
	)
	(footprint ""
		(layer "F.Cu")
		(at 36.930584 -107.539282)
		(property "Reference" "C2047"
			(at 0 0 0)
			(layer "F.SilkS")
			(hide yes)
			(effects
				(font
					(size 1.27 1.27)
				)
			)
		)
		(property "Value" ""
			(at 0 0 0)
			(layer "F.Fab")
			(effects
				(font
					(size 1.27 1.27)
				)
			)
		)
		(duplicate_pad_numbers_are_jumpers no)
		(fp_line
			(start -0.7874 -0.4064)
			(end 0.7874 -0.4064)
			(stroke
				(width 0.1524)
				(type default)
			)
			(layer "F.SilkS")
		)
		(fp_line
			(start -0.7874 0.4064)
			(end -0.7874 -0.4064)
			(stroke
				(width 0.1524)
				(type default)
			)
			(layer "F.SilkS")
		)
		(fp_line
			(start 0.7874 -0.4064)
			(end 0.7874 0.4064)
			(stroke
				(width 0.1524)
				(type default)
			)
			(layer "F.SilkS")
		)
		(fp_line
			(start 0.7874 0.4064)
			(end -0.7874 0.4064)
			(stroke
				(width 0.1524)
				(type default)
			)
			(layer "F.SilkS")
		)
		(fp_line
			(start -0.67945 -0.305054)
			(end -0.12065 -0.305054)
			(stroke
				(width 0.1)
				(type default)
			)
			(layer "F.Fab")
		)
		(fp_line
			(start -0.67945 0.3048)
			(end -0.67945 -0.305054)
			(stroke
				(width 0.1)
				(type default)
			)
			(layer "F.Fab")
		)
		(fp_line
			(start -0.12065 -0.305054)
			(end -0.12065 -0.2794)
			(stroke
				(width 0.1)
				(type default)
			)
			(layer "F.Fab")
		)
		(fp_line
			(start -0.12065 -0.2794)
			(end 0.12065 -0.2794)
			(stroke
				(width 0.1)
				(type default)
			)
			(layer "F.Fab")
		)
		(fp_line
			(start -0.12065 0.2794)
			(end -0.12065 0.3048)
			(stroke
				(width 0.1)
				(type default)
			)
			(layer "F.Fab")
		)
		(fp_line
			(start -0.12065 0.3048)
			(end -0.67945 0.3048)
			(stroke
				(width 0.1)
				(type default)
			)
			(layer "F.Fab")
		)
		(fp_line
			(start 0.120396 0.2794)
			(end -0.12065 0.2794)
			(stroke
				(width 0.1)
				(type default)
			)
			(layer "F.Fab")
		)
		(fp_line
			(start 0.120396 0.3048)
			(end 0.120396 0.2794)
			(stroke
				(width 0.1)
				(type default)
			)
			(layer "F.Fab")
		)
		(fp_line
			(start 0.12065 -0.3048)
			(end 0.67945 -0.3048)
			(stroke
				(width 0.1)
				(type default)
			)
			(layer "F.Fab")
		)
		(fp_line
			(start 0.12065 -0.2794)
			(end 0.12065 -0.3048)
			(stroke
				(width 0.1)
				(type default)
			)
			(layer "F.Fab")
		)
		(fp_line
			(start 0.67945 -0.3048)
			(end 0.67945 0.3048)
			(stroke
				(width 0.1)
				(type default)
			)
			(layer "F.Fab")
		)
		(fp_line
			(start 0.67945 0.3048)
			(end 0.120396 0.3048)
			(stroke
				(width 0.1)
				(type default)
			)
			(layer "F.Fab")
		)
		(pad "1" smd circle
			(at -0.40005 0)
			(size 0 0)
			(layers "F.Cu" "F.Mask" "F.Paste")
			(net "P3V3_AUX_ADC_TIC")
		)
		(pad "2" smd circle
			(at 0.40005 0)
			(size 0 0)
			(layers "F.Cu" "F.Mask" "F.Paste")
			(net "GND")
		)
	)
	(footprint ""
		(layer "F.Cu")
		(at 140.562076 -113.384584)
		(property "Reference" "U335"
			(at 0.4572 2.244852 0)
			(unlocked yes)
			(layer "F.SilkS")
			(effects
				(font
					(size 0.7874 0.5842)
					(thickness 0.1524)
				)
				(justify left)
			)
		)
		(property "Value" ""
			(at 0 0 0)
			(layer "F.Fab")
			(effects
				(font
					(size 1.27 1.27)
				)
			)
		)
		(duplicate_pad_numbers_are_jumpers no)
		(fp_line
			(start -1.733296 -1.549908)
			(end -1.733296 1.549908)
			(stroke
				(width 0.1524)
				(type default)
			)
			(layer "F.SilkS")
		)
		(fp_line
			(start -1.733296 1.549908)
			(end 1.733296 1.549908)
			(stroke
				(width 0.1524)
				(type default)
			)
			(layer "F.SilkS")
		)
		(fp_line
			(start -0.660908 -1.549908)
			(end -1.733296 -1.549908)
			(stroke
				(width 0.1524)
				(type default)
			)
			(layer "F.SilkS")
		)
		(fp_line
			(start 0 -0.889)
			(end -0.660908 -1.549908)
			(stroke
				(width 0.1524)
				(type default)
			)
			(layer "F.SilkS")
		)
		(fp_line
			(start 0.660908 -1.549908)
			(end 0 -0.889)
			(stroke
				(width 0.1524)
				(type default)
			)
			(layer "F.SilkS")
		)
		(fp_line
			(start 1.733296 -1.549908)
			(end 0.660908 -1.549908)
			(stroke
				(width 0.1524)
				(type default)
			)
			(layer "F.SilkS")
		)
		(fp_line
			(start 1.733296 1.549908)
			(end 1.733296 -1.549908)
			(stroke
				(width 0.1524)
				(type default)
			)
			(layer "F.SilkS")
		)
		(fp_poly
			(pts
				(xy -2.064512 -1.853438) (xy -2.423922 -1.494282) (xy -1.884934 -1.314704)
			)
			(stroke
				(width 0)
				(type default)
			)
			(fill yes)
			(layer "F.SilkS")
		)
		(fp_line
			(start -0.849884 -1.549908)
			(end -0.849884 1.549908)
			(stroke
				(width 0.1)
				(type default)
			)
			(layer "F.Fab")
		)
		(fp_line
			(start -0.849884 1.549908)
			(end 0.849884 1.549908)
			(stroke
				(width 0.1)
				(type default)
			)
			(layer "F.Fab")
		)
		(fp_line
			(start 0.849884 -1.549908)
			(end -0.849884 -1.549908)
			(stroke
				(width 0.1)
				(type default)
			)
			(layer "F.Fab")
		)
		(fp_line
			(start 0.849884 1.549908)
			(end 0.849884 -1.549908)
			(stroke
				(width 0.1)
				(type default)
			)
			(layer "F.Fab")
		)
		(fp_poly
			(pts
				(xy -2.4384 -1.20396) (xy -2.4384 -0.69596) (xy -1.9304 -0.94996)
			)
			(stroke
				(width 0)
				(type default)
			)
			(fill yes)
			(layer "F.Fab")
		)
		(pad "1" smd rect
			(at -1.199896 -0.94996 270)
			(size 0.5588 0.8128)
			(layers "F.Cu" "F.Mask" "F.Paste")
			(net "HP_LVC3_OCP_V3_2_PWRGD_R2")
		)
		(pad "2" smd rect
			(at -1.199896 0 270)
			(size 0.5588 0.8128)
			(layers "F.Cu" "F.Mask" "F.Paste")
			(net "OCP_V3_2_AUX_PWR_PLD_EN_R")
		)
		(pad "3" smd rect
			(at -1.199896 0.94996 270)
			(size 0.5588 0.8128)
			(layers "F.Cu" "F.Mask" "F.Paste")
			(net "GND")
		)
		(pad "4" smd rect
			(at 1.199896 0.94996 270)
			(size 0.5588 0.8128)
			(layers "F.Cu" "F.Mask" "F.Paste")
			(net "OCP_V3_2_AUX_PWR_EN_R2")
		)
		(pad "5" smd rect
			(at 1.199896 -0.94996 270)
			(size 0.5588 0.8128)
			(layers "F.Cu" "F.Mask" "F.Paste")
			(net "P3V3_AUX")
		)
	)
	(footprint ""
		(layer "F.Cu")
		(at 364.50143 -258.726686 90)
		(property "Reference" "C968"
			(at 0 0 90)
			(layer "F.SilkS")
			(hide yes)
			(effects
				(font
					(size 1.27 1.27)
				)
			)
		)
		(property "Value" ""
			(at 0 0 90)
			(layer "F.Fab")
			(effects
				(font
					(size 1.27 1.27)
				)
			)
		)
		(duplicate_pad_numbers_are_jumpers no)
		(fp_line
			(start 0.7874 -0.4064)
			(end 0.7874 0.4064)
			(stroke
				(width 0.1524)
				(type default)
			)
			(layer "F.SilkS")
		)
		(fp_line
			(start -0.7874 -0.4064)
			(end 0.7874 -0.4064)
			(stroke
				(width 0.1524)
				(type default)
			)
			(layer "F.SilkS")
		)
		(fp_line
			(start 0.7874 0.4064)
			(end -0.7874 0.4064)
			(stroke
				(width 0.1524)
				(type default)
			)
			(layer "F.SilkS")
		)
		(fp_line
			(start -0.7874 0.4064)
			(end -0.7874 -0.4064)
			(stroke
				(width 0.1524)
				(type default)
			)
			(layer "F.SilkS")
		)
		(fp_line
			(start -0.12065 -0.305054)
			(end -0.12065 -0.2794)
			(stroke
				(width 0.1)
				(type default)
			)
			(layer "F.Fab")
		)
		(fp_line
			(start -0.67945 -0.305054)
			(end -0.12065 -0.305054)
			(stroke
				(width 0.1)
				(type default)
			)
			(layer "F.Fab")
		)
		(fp_line
			(start 0.67945 -0.3048)
			(end 0.67945 0.3048)
			(stroke
				(width 0.1)
				(type default)
			)
			(layer "F.Fab")
		)
		(fp_line
			(start 0.12065 -0.3048)
			(end 0.67945 -0.3048)
			(stroke
				(width 0.1)
				(type default)
			)
			(layer "F.Fab")
		)
		(fp_line
			(start 0.12065 -0.2794)
			(end 0.12065 -0.3048)
			(stroke
				(width 0.1)
				(type default)
			)
			(layer "F.Fab")
		)
		(fp_line
			(start -0.12065 -0.2794)
			(end 0.12065 -0.2794)
			(stroke
				(width 0.1)
				(type default)
			)
			(layer "F.Fab")
		)
		(fp_line
			(start 0.120396 0.2794)
			(end -0.12065 0.2794)
			(stroke
				(width 0.1)
				(type default)
			)
			(layer "F.Fab")
		)
		(fp_line
			(start -0.12065 0.2794)
			(end -0.12065 0.3048)
			(stroke
				(width 0.1)
				(type default)
			)
			(layer "F.Fab")
		)
		(fp_line
			(start 0.67945 0.3048)
			(end 0.120396 0.3048)
			(stroke
				(width 0.1)
				(type default)
			)
			(layer "F.Fab")
		)
		(fp_line
			(start 0.120396 0.3048)
			(end 0.120396 0.2794)
			(stroke
				(width 0.1)
				(type default)
			)
			(layer "F.Fab")
		)
		(fp_line
			(start -0.12065 0.3048)
			(end -0.67945 0.3048)
			(stroke
				(width 0.1)
				(type default)
			)
			(layer "F.Fab")
		)
		(fp_line
			(start -0.67945 0.3048)
			(end -0.67945 -0.305054)
			(stroke
				(width 0.1)
				(type default)
			)
			(layer "F.Fab")
		)
		(pad "1" smd circle
			(at -0.40005 0 90)
			(size 0 0)
			(layers "F.Cu" "F.Mask" "F.Paste")
			(net "PVCCIN_CPU0")
		)
		(pad "2" smd circle
			(at 0.40005 0 90)
			(size 0 0)
			(layers "F.Cu" "F.Mask" "F.Paste")
			(net "GND")
		)
	)
	(footprint ""
		(layer "F.Cu")
		(at 351.116138 -354.483162 90)
		(property "Reference" "R4216"
			(at 0 0 90)
			(layer "F.SilkS")
			(hide yes)
			(effects
				(font
					(size 1.27 1.27)
				)
			)
		)
		(property "Value" ""
			(at 0 0 90)
			(layer "F.Fab")
			(effects
				(font
					(size 1.27 1.27)
				)
			)
		)
		(duplicate_pad_numbers_are_jumpers no)
		(fp_line
			(start 0.7874 -0.4064)
			(end 0.7874 0.4064)
			(stroke
				(width 0.1524)
				(type default)
			)
			(layer "F.SilkS")
		)
		(fp_line
			(start -0.7874 -0.4064)
			(end 0.7874 -0.4064)
			(stroke
				(width 0.1524)
				(type default)
			)
			(layer "F.SilkS")
		)
		(fp_line
			(start 0.7874 0.4064)
			(end -0.7874 0.4064)
			(stroke
				(width 0.1524)
				(type default)
			)
			(layer "F.SilkS")
		)
		(fp_line
			(start -0.7874 0.4064)
			(end -0.7874 -0.4064)
			(stroke
				(width 0.1524)
				(type default)
			)
			(layer "F.SilkS")
		)
		(fp_line
			(start -0.12065 -0.305054)
			(end -0.12065 -0.2794)
			(stroke
				(width 0.1)
				(type default)
			)
			(layer "F.Fab")
		)
		(fp_line
			(start -0.67945 -0.305054)
			(end -0.12065 -0.305054)
			(stroke
				(width 0.1)
				(type default)
			)
			(layer "F.Fab")
		)
		(fp_line
			(start 0.67945 -0.3048)
			(end 0.67945 0.3048)
			(stroke
				(width 0.1)
				(type default)
			)
			(layer "F.Fab")
		)
		(fp_line
			(start 0.12065 -0.3048)
			(end 0.67945 -0.3048)
			(stroke
				(width 0.1)
				(type default)
			)
			(layer "F.Fab")
		)
		(fp_line
			(start 0.12065 -0.2794)
			(end 0.12065 -0.3048)
			(stroke
				(width 0.1)
				(type default)
			)
			(layer "F.Fab")
		)
		(fp_line
			(start -0.12065 -0.2794)
			(end 0.12065 -0.2794)
			(stroke
				(width 0.1)
				(type default)
			)
			(layer "F.Fab")
		)
		(fp_line
			(start 0.120396 0.2794)
			(end -0.12065 0.2794)
			(stroke
				(width 0.1)
				(type default)
			)
			(layer "F.Fab")
		)
		(fp_line
			(start -0.12065 0.2794)
			(end -0.12065 0.3048)
			(stroke
				(width 0.1)
				(type default)
			)
			(layer "F.Fab")
		)
		(fp_line
			(start 0.67945 0.3048)
			(end 0.120396 0.3048)
			(stroke
				(width 0.1)
				(type default)
			)
			(layer "F.Fab")
		)
		(fp_line
			(start 0.120396 0.3048)
			(end 0.120396 0.2794)
			(stroke
				(width 0.1)
				(type default)
			)
			(layer "F.Fab")
		)
		(fp_line
			(start -0.12065 0.3048)
			(end -0.67945 0.3048)
			(stroke
				(width 0.1)
				(type default)
			)
			(layer "F.Fab")
		)
		(fp_line
			(start -0.67945 0.3048)
			(end -0.67945 -0.305054)
			(stroke
				(width 0.1)
				(type default)
			)
			(layer "F.Fab")
		)
		(pad "1" smd circle
			(at -0.40005 0 90)
			(size 0 0)
			(layers "F.Cu" "F.Mask" "F.Paste")
			(net "FM_PVCCFA_EHV_FIVRA_CPU0_EN")
		)
		(pad "2" smd circle
			(at 0.40005 0 90)
			(size 0 0)
			(layers "F.Cu" "F.Mask" "F.Paste")
			(net "PVCCFA_EHV_FIVRA_CPU0_EN_R")
		)
	)
)
